# S9S_MB_2U (Grand Teton) — schematic netlist excerpt (pin names and nets, part order shuffled) for the footprints in the layout excerpt that follows; sources: Cadence DE-HDL packaged netlist, KiCad conversion of 03242023_DA0F0TMBIJ0_F0T_Motherboard_J_brd_V01_OCP.brd

R4632  Q_RES  0 5% CHIP  pkg 0402LF  page 248 : A = JTAG_BMC_SW_TMS_R ; B = JTAG_BMC_SW_TMS

X14  TP_TDR_4P_FTS  TP_TDR_4P_DIP EMPTY  pkg TH  page 309
  S1  = TDR_DIFF_100_IN1_DP
  P1  = T1_GND
  P2  = T1_GND
  S2  = TDR_DIFF_100_IN1_DN

(kicad_pcb
	(version 20260206)
	(generator "pcbnew")
	(generator_version "10.0")
	(general
		(thickness 1.6)
		(legacy_teardrops no)
	)
	(paper "A4")
	(title_block
		(title "03242023_DA0F0TMBIJ0_F0T_Motherboard_J_brd_V01_OCP.brd")
		(comment 1 "Grand Teton / footprints 3371-3372 of 6105")
	)
	(layers
		(0 "F.Cu" signal "TOP")
		(4 "In1.Cu" signal "GND")
		(6 "In2.Cu" signal "IN1")
		(8 "In3.Cu" signal "GND1")
		(10 "In4.Cu" signal "IN2")
		(12 "In5.Cu" signal "GND2")
		(14 "In6.Cu" signal "IN3")
		(16 "In7.Cu" signal "GND3")
		(18 "In8.Cu" signal "VCC")
		(20 "In9.Cu" signal "VCC1")
		(22 "In10.Cu" signal "GND4")
		(24 "In11.Cu" signal "IN4")
		(26 "In12.Cu" signal "GND5")
		(28 "In13.Cu" signal "IN5")
		(30 "In14.Cu" signal "GND6")
		(32 "In15.Cu" signal "IN6")
		(34 "In16.Cu" signal "GND7")
		(2 "B.Cu" signal "BOTTOM")
		(9 "F.Adhes" user "F.Adhesive")
		(11 "B.Adhes" user "B.Adhesive")
		(13 "F.Paste" user "Package Geometry/Pastemask Top")
		(15 "B.Paste" user "Package Geometry/Pastemask Bottom")
		(5 "F.SilkS" user "Ref Des/Silkscreen Top")
		(7 "B.SilkS" user "Ref Des/Silkscreen Bottom")
		(1 "F.Mask" user "Board Geometry/Soldermask Top")
		(3 "B.Mask" user "Board Geometry/Soldermask Bottom")
		(17 "Dwgs.User" user "User.Drawings")
		(19 "Cmts.User" user "User.Comments")
		(21 "Eco1.User" user "User.Eco1")
		(23 "Eco2.User" user "User.Eco2")
		(25 "Edge.Cuts" user "Board Geometry/Outline")
		(27 "Margin" user)
		(31 "F.CrtYd" user "Package Geometry/Place Bound Top")
		(29 "B.CrtYd" user "Package Geometry/Place Bound Bottom")
		(35 "F.Fab" user "Ref Des/Assembly Top")
		(33 "B.Fab" user "Ref Des/Assembly Bottom")
	)
	(footprint ""
		(layer "F.Cu")
		(at 509.384808 -148.08708 90)
		(property "Reference" "X14"
			(at -3.417316 3.094482 90)
			(unlocked yes)
			(layer "F.SilkS")
			(effects
				(font
					(size 0.7874 0.5842)
					(thickness 0.1524)
				)
				(justify left)
			)
		)
		(property "Value" ""
			(at 0 0 90)
			(layer "F.Fab")
			(effects
				(font
					(size 1.27 1.27)
				)
			)
		)
		(property "Device Type" "TP_TDR_4P_FTS_MPKT4_H025P0200_I"
			(at 1.30175 1.27 180)
			(unlocked yes)
			(layer "F.Fab")
			(hide yes)
			(effects
				(font
					(size 0.635 0.4064)
					(thickness 0.1524)
				)
			)
		)
		(property "User Part Number" "TP15"
			(at 1.30175 1.27 180)
			(unlocked yes)
			(layer "Cmts.User")
			(hide yes)
			(effects
				(font
					(size 0.635 0.4064)
					(thickness 0.1524)
				)
			)
		)
		(duplicate_pad_numbers_are_jumpers no)
		(fp_line
			(start 2.54 -1.27)
			(end 0 -1.27)
			(stroke
				(width 0.1524)
				(type default)
			)
			(layer "F.SilkS")
		)
		(fp_line
			(start 0 -1.27)
			(end 0 -0.635)
			(stroke
				(width 0.1524)
				(type default)
			)
			(layer "F.SilkS")
		)
		(fp_line
			(start 2.54 -1.1303)
			(end 2.54 -1.27)
			(stroke
				(width 0.1524)
				(type default)
			)
			(layer "F.SilkS")
		)
		(fp_line
			(start 0 0.635)
			(end 0 1.905)
			(stroke
				(width 0.1524)
				(type default)
			)
			(layer "F.SilkS")
		)
		(fp_line
			(start 2.54 1.4097)
			(end 2.54 1.1303)
			(stroke
				(width 0.1524)
				(type default)
			)
			(layer "F.SilkS")
		)
		(fp_line
			(start 0 3.175)
			(end 0 3.81)
			(stroke
				(width 0.1524)
				(type default)
			)
			(layer "F.SilkS")
		)
		(fp_line
			(start 2.54 3.81)
			(end 2.54 3.6703)
			(stroke
				(width 0.1524)
				(type default)
			)
			(layer "F.SilkS")
		)
		(fp_line
			(start 0 3.81)
			(end 2.54 3.81)
			(stroke
				(width 0.1524)
				(type default)
			)
			(layer "F.SilkS")
		)
		(fp_poly
			(pts
				(xy -1.267206 -0.04064) (xy -2.791206 0.72136) (xy -2.791206 -0.80264)
			)
			(stroke
				(width 0)
				(type default)
			)
			(fill yes)
			(layer "F.SilkS")
		)
		(fp_line
			(start 2.54 -1.27)
			(end 0 -1.27)
			(stroke
				(width 0.1)
				(type default)
			)
			(layer "F.Fab")
		)
		(fp_line
			(start 0 -1.27)
			(end 0 3.81)
			(stroke
				(width 0.1)
				(type default)
			)
			(layer "F.Fab")
		)
		(fp_line
			(start 2.54 3.81)
			(end 2.54 -1.27)
			(stroke
				(width 0.1)
				(type default)
			)
			(layer "F.Fab")
		)
		(fp_line
			(start 0 3.81)
			(end 2.54 3.81)
			(stroke
				(width 0.1)
				(type default)
			)
			(layer "F.Fab")
		)
		(fp_poly
			(pts
				(xy -0.761746 0) (xy -2.285746 -0.762) (xy -2.285746 0.762)
			)
			(stroke
				(width 0)
				(type default)
			)
			(fill yes)
			(layer "F.Fab")
		)
		(pad "1" thru_hole circle
			(at 0 0 90)
			(size 1.0033 1.0033)
			(drill 0.249936)
			(layers "*.Cu" "*.Mask")
			(remove_unused_layers no)
			(net "TDR_DIFF_100_IN1_DP")
			(clearance 0.10795)
			(thermal_gap 0.10795)
			(padstack
				(mode front_inner_back)
				(layer "Inner"
					(shape circle)
					(size 0.8001 0.8001)
					(clearance 0.1524)
				)
				(layer "B.Cu"
					(shape circle)
					(size 1.0033 1.0033)
					(clearance 0.10795)
				)
			)
		)
		(pad "2" thru_hole circle
			(at 2.54 0 90)
			(size 1.9939 1.9939)
			(drill 0.249936)
			(layers "*.Cu" "*.Mask")
			(remove_unused_layers no)
			(net "T1_GND")
			(clearance 0.10795)
			(thermal_gap 0.10795)
			(padstack
				(mode front_inner_back)
				(layer "Inner"
					(shape circle)
					(size 0.8001 0.8001)
					(clearance 0.1524)
				)
				(layer "B.Cu"
					(shape circle)
					(size 1.9939 1.9939)
					(clearance 0.10795)
				)
			)
		)
		(pad "3" thru_hole circle
			(at 2.54 2.54 90)
			(size 1.9939 1.9939)
			(drill 0.249936)
			(layers "*.Cu" "*.Mask")
			(remove_unused_layers no)
			(net "T1_GND")
			(clearance 0.10795)
			(thermal_gap 0.10795)
			(padstack
				(mode front_inner_back)
				(layer "Inner"
					(shape circle)
					(size 0.8001 0.8001)
					(clearance 0.1524)
				)
				(layer "B.Cu"
					(shape circle)
					(size 1.9939 1.9939)
					(clearance 0.10795)
				)
			)
		)
		(pad "4" thru_hole circle
			(at 0 2.54 90)
			(size 1.0033 1.0033)
			(drill 0.249936)
			(layers "*.Cu" "*.Mask")
			(remove_unused_layers no)
			(net "TDR_DIFF_100_IN1_DN")
			(clearance 0.10795)
			(thermal_gap 0.10795)
			(padstack
				(mode front_inner_back)
				(layer "Inner"
					(shape circle)
					(size 0.8001 0.8001)
					(clearance 0.1524)
				)
				(layer "B.Cu"
					(shape circle)
					(size 1.0033 1.0033)
					(clearance 0.10795)
				)
			)
		)
	)
	(footprint ""
		(layer "F.Cu")
		(at 115.951 -54.193948 180)
		(property "Reference" "R4632"
			(at 0 0 180)
			(layer "F.SilkS")
			(hide yes)
			(effects
				(font
					(size 1.27 1.27)
				)
			)
		)
		(property "Value" ""
			(at 0 0 180)
			(layer "F.Fab")
			(effects
				(font
					(size 1.27 1.27)
				)
			)
		)
		(duplicate_pad_numbers_are_jumpers no)
		(fp_line
			(start 0.7874 0.4064)
			(end -0.7874 0.4064)
			(stroke
				(width 0.1524)
				(type default)
			)
			(layer "F.SilkS")
		)
		(fp_line
			(start 0.7874 -0.4064)
			(end 0.7874 0.4064)
			(stroke
				(width 0.1524)
				(type default)
			)
			(layer "F.SilkS")
		)
		(fp_line
			(start -0.7874 0.4064)
			(end -0.7874 -0.4064)
			(stroke
				(width 0.1524)
				(type default)
			)
			(layer "F.SilkS")
		)
		(fp_line
			(start -0.7874 -0.4064)
			(end 0.7874 -0.4064)
			(stroke
				(width 0.1524)
				(type default)
			)
			(layer "F.SilkS")
		)
		(fp_line
			(start 0.67945 0.3048)
			(end 0.120396 0.3048)
			(stroke
				(width 0.1)
				(type default)
			)
			(layer "F.Fab")
		)
		(fp_line
			(start 0.67945 -0.3048)
			(end 0.67945 0.3048)
			(stroke
				(width 0.1)
				(type default)
			)
			(layer "F.Fab")
		)
		(fp_line
			(start 0.12065 -0.2794)
			(end 0.12065 -0.3048)
			(stroke
				(width 0.1)
				(type default)
			)
			(layer "F.Fab")
		)
		(fp_line
			(start 0.12065 -0.3048)
			(end 0.67945 -0.3048)
			(stroke
				(width 0.1)
				(type default)
			)
			(layer "F.Fab")
		)
		(fp_line
			(start 0.120396 0.3048)
			(end 0.120396 0.2794)
			(stroke
				(width 0.1)
				(type default)
			)
			(layer "F.Fab")
		)
		(fp_line
			(start 0.120396 0.2794)
			(end -0.12065 0.2794)
			(stroke
				(width 0.1)
				(type default)
			)
			(layer "F.Fab")
		)
		(fp_line
			(start -0.12065 0.3048)
			(end -0.67945 0.3048)
			(stroke
				(width 0.1)
				(type default)
			)
			(layer "F.Fab")
		)
		(fp_line
			(start -0.12065 0.2794)
			(end -0.12065 0.3048)
			(stroke
				(width 0.1)
				(type default)
			)
			(layer "F.Fab")
		)
		(fp_line
			(start -0.12065 -0.2794)
			(end 0.12065 -0.2794)
			(stroke
				(width 0.1)
				(type default)
			)
			(layer "F.Fab")
		)
		(fp_line
			(start -0.12065 -0.305054)
			(end -0.12065 -0.2794)
			(stroke
				(width 0.1)
				(type default)
			)
			(layer "F.Fab")
		)
		(fp_line
			(start -0.67945 0.3048)
			(end -0.67945 -0.305054)
			(stroke
				(width 0.1)
				(type default)
			)
			(layer "F.Fab")
		)
		(fp_line
			(start -0.67945 -0.305054)
			(end -0.12065 -0.305054)
			(stroke
				(width 0.1)
				(type default)
			)
			(layer "F.Fab")
		)
		(pad "1" smd circle
			(at -0.40005 0 180)
			(size 0 0)
			(layers "F.Cu" "F.Mask" "F.Paste")
			(net "JTAG_BMC_SW_TMS_R")
		)
		(pad "2" smd circle
			(at 0.40005 0 180)
			(size 0 0)
			(layers "F.Cu" "F.Mask" "F.Paste")
			(net "JTAG_BMC_SW_TMS")
		)
	)
)
